# S9S_MB_2U (Grand Teton) — schematic netlist excerpt (pin names and nets, part order shuffled) for the footprints in the layout excerpt that follows; sources: Cadence DE-HDL packaged netlist, KiCad conversion of 03242023_DA0F0TMBIJ0_F0T_Motherboard_J_brd_V01_OCP.brd

C1977  Q_CAP  0.1UF 25V 10% X7R  pkg 0402  page 149 : A = P3V3_AUX ; B = GND

(kicad_pcb
	(version 20260206)
	(generator "pcbnew")
	(generator_version "10.0")
	(general
		(thickness 1.6)
		(legacy_teardrops no)
	)
	(paper "A4")
	(title_block
		(title "03242023_DA0F0TMBIJ0_F0T_Motherboard_J_brd_V01_OCP.brd")
		(comment 1 "Grand Teton / footprints 1252-1252 of 6105")
	)
	(layers
		(0 "F.Cu" signal "TOP")
		(4 "In1.Cu" signal "GND")
		(6 "In2.Cu" signal "IN1")
		(8 "In3.Cu" signal "GND1")
		(10 "In4.Cu" signal "IN2")
		(12 "In5.Cu" signal "GND2")
		(14 "In6.Cu" signal "IN3")
		(16 "In7.Cu" signal "GND3")
		(18 "In8.Cu" signal "VCC")
		(20 "In9.Cu" signal "VCC1")
		(22 "In10.Cu" signal "GND4")
		(24 "In11.Cu" signal "IN4")
		(26 "In12.Cu" signal "GND5")
		(28 "In13.Cu" signal "IN5")
		(30 "In14.Cu" signal "GND6")
		(32 "In15.Cu" signal "IN6")
		(34 "In16.Cu" signal "GND7")
		(2 "B.Cu" signal "BOTTOM")
		(9 "F.Adhes" user "F.Adhesive")
		(11 "B.Adhes" user "B.Adhesive")
		(13 "F.Paste" user "Package Geometry/Pastemask Top")
		(15 "B.Paste" user "Package Geometry/Pastemask Bottom")
		(5 "F.SilkS" user "Ref Des/Silkscreen Top")
		(7 "B.SilkS" user "Ref Des/Silkscreen Bottom")
		(1 "F.Mask" user "Board Geometry/Soldermask Top")
		(3 "B.Mask" user "Board Geometry/Soldermask Bottom")
		(17 "Dwgs.User" user "User.Drawings")
		(19 "Cmts.User" user "User.Comments")
		(21 "Eco1.User" user "User.Eco1")
		(23 "Eco2.User" user "User.Eco2")
		(25 "Edge.Cuts" user "Board Geometry/Outline")
		(27 "Margin" user)
		(31 "F.CrtYd" user "Package Geometry/Place Bound Top")
		(29 "B.CrtYd" user "Package Geometry/Place Bound Bottom")
		(35 "F.Fab" user "Ref Des/Assembly Top")
		(33 "B.Fab" user "Ref Des/Assembly Bottom")
	)
	(footprint ""
		(layer "F.Cu")
		(at 29.51988 -430.875948)
		(property "Reference" "C1977"
			(at 0 0 0)
			(layer "F.SilkS")
			(hide yes)
			(effects
				(font
					(size 1.27 1.27)
				)
			)
		)
		(property "Value" ""
			(at 0 0 0)
			(layer "F.Fab")
			(effects
				(font
					(size 1.27 1.27)
				)
			)
		)
		(duplicate_pad_numbers_are_jumpers no)
		(fp_line
			(start -0.7874 -0.4064)
			(end 0.7874 -0.4064)
			(stroke
				(width 0.1524)
				(type default)
			)
			(layer "F.SilkS")
		)
		(fp_line
			(start -0.7874 0.4064)
			(end -0.7874 -0.4064)
			(stroke
				(width 0.1524)
				(type default)
			)
			(layer "F.SilkS")
		)
		(fp_line
			(start 0.7874 -0.4064)
			(end 0.7874 0.4064)
			(stroke
				(width 0.1524)
				(type default)
			)
			(layer "F.SilkS")
		)
		(fp_line
			(start 0.7874 0.4064)
			(end -0.7874 0.4064)
			(stroke
				(width 0.1524)
				(type default)
			)
			(layer "F.SilkS")
		)
		(fp_line
			(start -0.67945 -0.305054)
			(end -0.12065 -0.305054)
			(stroke
				(width 0.1)
				(type default)
			)
			(layer "F.Fab")
		)
		(fp_line
			(start -0.67945 0.3048)
			(end -0.67945 -0.305054)
			(stroke
				(width 0.1)
				(type default)
			)
			(layer "F.Fab")
		)
		(fp_line
			(start -0.12065 -0.305054)
			(end -0.12065 -0.2794)
			(stroke
				(width 0.1)
				(type default)
			)
			(layer "F.Fab")
		)
		(fp_line
			(start -0.12065 -0.2794)
			(end 0.12065 -0.2794)
			(stroke
				(width 0.1)
				(type default)
			)
			(layer "F.Fab")
		)
		(fp_line
			(start -0.12065 0.2794)
			(end -0.12065 0.3048)
			(stroke
				(width 0.1)
				(type default)
			)
			(layer "F.Fab")
		)
		(fp_line
			(start -0.12065 0.3048)
			(end -0.67945 0.3048)
			(stroke
				(width 0.1)
				(type default)
			)
			(layer "F.Fab")
		)
		(fp_line
			(start 0.120396 0.2794)
			(end -0.12065 0.2794)
			(stroke
				(width 0.1)
				(type default)
			)
			(layer "F.Fab")
		)
		(fp_line
			(start 0.120396 0.3048)
			(end 0.120396 0.2794)
			(stroke
				(width 0.1)
				(type default)
			)
			(layer "F.Fab")
		)
		(fp_line
			(start 0.12065 -0.3048)
			(end 0.67945 -0.3048)
			(stroke
				(width 0.1)
				(type default)
			)
			(layer "F.Fab")
		)
		(fp_line
			(start 0.12065 -0.2794)
			(end 0.12065 -0.3048)
			(stroke
				(width 0.1)
				(type default)
			)
			(layer "F.Fab")
		)
		(fp_line
			(start 0.67945 -0.3048)
			(end 0.67945 0.3048)
			(stroke
				(width 0.1)
				(type default)
			)
			(layer "F.Fab")
		)
		(fp_line
			(start 0.67945 0.3048)
			(end 0.120396 0.3048)
			(stroke
				(width 0.1)
				(type default)
			)
			(layer "F.Fab")
		)
		(pad "1" smd circle
			(at -0.40005 0)
			(size 0 0)
			(layers "F.Cu" "F.Mask" "F.Paste")
			(net "P3V3_AUX")
		)
		(pad "2" smd circle
			(at 0.40005 0)
			(size 0 0)
			(layers "F.Cu" "F.Mask" "F.Paste")
			(net "GND")
		)
	)
)
